(kicad_pcb
	(version 20260206)
	(generator "pcbnew")
	(generator_version "10.0")
	(general
		(thickness 1.6)
		(legacy_teardrops no)
	)
	(paper "A4")
	(title_block
		(title "Bryce Canyon_IOM_M2_16342-2_OCP.brd")
		(comment 1 "Bryce Canyon / footprints 977-983 of 1146")
	)
	(layers
		(0 "F.Cu" signal "TOP")
		(4 "In1.Cu" signal "L2GND")
		(6 "In2.Cu" signal "L3")
		(8 "In3.Cu" signal "L4VCC")
		(10 "In4.Cu" signal "L5VCC")
		(12 "In5.Cu" signal "L6")
		(14 "In6.Cu" signal "L7GND")
		(2 "B.Cu" signal "BOTTOM")
		(9 "F.Adhes" user "F.Adhesive")
		(11 "B.Adhes" user "B.Adhesive")
		(13 "F.Paste" user "Package Geometry/Pastemask Top")
		(15 "B.Paste" user "Package Geometry/Pastemask Bottom")
		(5 "F.SilkS" user "Ref Des/Silkscreen Top")
		(7 "B.SilkS" user "Ref Des/Silkscreen Bottom")
		(1 "F.Mask" user "Board Geometry/Soldermask Top")
		(3 "B.Mask" user "Board Geometry/Soldermask Bottom")
		(17 "Dwgs.User" user "User.Drawings")
		(19 "Cmts.User" user "User.Comments")
		(21 "Eco1.User" user "User.Eco1")
		(23 "Eco2.User" user "User.Eco2")
		(25 "Edge.Cuts" user "Board Geometry/Outline")
		(27 "Margin" user)
		(31 "F.CrtYd" user "Package Geometry/Place Bound Top")
		(29 "B.CrtYd" user "Package Geometry/Place Bound Bottom")
		(35 "F.Fab" user "Ref Des/Assembly Top")
		(33 "B.Fab" user "Ref Des/Assembly Bottom")
	)
	(footprint ""
		(layer "B.Cu")
		(at 96.52 -152.4254 180)
		(property "Reference" "R42"
			(at 0 0 0)
			(layer "B.SilkS")
			(hide yes)
			(effects
				(font
					(size 1.27 1.27)
				)
				(justify mirror)
			)
		)
		(property "Value" "4K7R2F-GP"
			(at -0.064008 -3.993896 180)
			(unlocked yes)
			(layer "B.Fab")
			(hide yes)
			(effects
				(font
					(size 1.016 1.016)
					(thickness 0.1524)
				)
				(justify mirror)
			)
		)
		(property "Device Type" "R402H16"
			(at -0.064008 -5.517896 180)
			(unlocked yes)
			(layer "B.Fab")
			(hide yes)
			(effects
				(font
					(size 1.016 1.016)
					(thickness 0.1524)
				)
				(justify mirror)
			)
		)
		(duplicate_pad_numbers_are_jumpers no)
		(fp_line
			(start 0.508 -0.9398)
			(end 0.508 0.9398)
			(stroke
				(width 0.1524)
				(type default)
			)
			(layer "B.SilkS")
		)
		(fp_line
			(start -0.508 -0.9398)
			(end 0.508 -0.9398)
			(stroke
				(width 0.1524)
				(type default)
			)
			(layer "B.SilkS")
		)
		(fp_rect
			(start 0.508 0.9398)
			(end -0.508 -0.9398)
			(stroke
				(width 0)
				(type default)
			)
			(fill no)
			(layer "B.CrtYd")
		)
		(fp_rect
			(start 0.508 0.9398)
			(end -0.508 -0.9398)
			(stroke
				(width 0)
				(type default)
			)
			(fill no)
			(layer "B.Fab")
		)
		(pad "1" smd custom
			(at 0 -0.4445)
			(size 0.1397 0.1397)
			(layers "B.Cu" "B.Mask" "B.Paste")
			(net "USB_EN_3")
			(options
				(clearance outline)
				(anchor circle)
			)
			(primitives
				(gr_poly
					(pts
						(arc
							(start -0.1778 0.2794)
							(mid -0.249642 0.249642)
							(end -0.2794 0.1778)
						)
						(arc
							(start -0.2794 -0.1778)
							(mid -0.249642 -0.249642)
							(end -0.1778 -0.2794)
						)
						(arc
							(start 0.1778 -0.2794)
							(mid 0.249642 -0.249642)
							(end 0.2794 -0.1778)
						)
						(arc
							(start 0.2794 0.1778)
							(mid 0.249642 0.249642)
							(end 0.1778 0.2794)
						)
					)
					(width 0)
					(fill yes)
				)
			)
		)
		(pad "2" smd custom
			(at 0 0.4445)
			(size 0.1397 0.1397)
			(layers "B.Cu" "B.Mask" "B.Paste")
			(net "GND")
			(options
				(clearance outline)
				(anchor circle)
			)
			(primitives
				(gr_poly
					(pts
						(arc
							(start -0.1778 0.2794)
							(mid -0.249642 0.249642)
							(end -0.2794 0.1778)
						)
						(arc
							(start -0.2794 -0.1778)
							(mid -0.249642 -0.249642)
							(end -0.1778 -0.2794)
						)
						(arc
							(start 0.1778 -0.2794)
							(mid 0.249642 -0.249642)
							(end 0.2794 -0.1778)
						)
						(arc
							(start 0.2794 0.1778)
							(mid 0.249642 0.249642)
							(end 0.1778 0.2794)
						)
					)
					(width 0)
					(fill yes)
				)
			)
		)
	)
	(footprint ""
		(layer "B.Cu")
		(at 44.137326 -147.30476 90)
		(property "Reference" "C53"
			(at 0 0 90)
			(layer "B.SilkS")
			(hide yes)
			(effects
				(font
					(size 1.27 1.27)
				)
				(justify mirror)
			)
		)
		(property "Value" "SCD01U25V2KX-3GP"
			(at -1.1811 -2.7051 90)
			(unlocked yes)
			(layer "B.Fab")
			(hide yes)
			(effects
				(font
					(size 1.016 1.016)
					(thickness 0.1524)
				)
				(justify mirror)
			)
		)
		(property "Device Type" "C402H22"
			(at -1.1811 -4.2291 90)
			(unlocked yes)
			(layer "B.Fab")
			(hide yes)
			(effects
				(font
					(size 1.016 1.016)
					(thickness 0.1524)
				)
				(justify mirror)
			)
		)
		(duplicate_pad_numbers_are_jumpers no)
		(fp_rect
			(start 0.4318 0.9525)
			(end -0.4318 -0.9525)
			(stroke
				(width 0)
				(type default)
			)
			(fill no)
			(layer "B.CrtYd")
		)
		(fp_rect
			(start 0.4318 0.9525)
			(end -0.4318 -0.9525)
			(stroke
				(width 0)
				(type default)
			)
			(fill no)
			(layer "B.Fab")
		)
		(pad "1" smd custom
			(at 0 -0.4445 270)
			(size 0.1524 0.1524)
			(layers "B.Cu" "B.Mask" "B.Paste")
			(net "DDR_VREF")
			(options
				(clearance outline)
				(anchor circle)
			)
			(primitives
				(gr_poly
					(pts
						(arc
							(start 0.3048 0.2032)
							(mid 0.275042 0.275042)
							(end 0.2032 0.3048)
						)
						(arc
							(start -0.2032 0.3048)
							(mid -0.275042 0.275042)
							(end -0.3048 0.2032)
						)
						(arc
							(start -0.3048 -0.2032)
							(mid -0.275042 -0.275042)
							(end -0.2032 -0.3048)
						)
						(arc
							(start 0.2032 -0.3048)
							(mid 0.275042 -0.275042)
							(end 0.3048 -0.2032)
						)
					)
					(width 0)
					(fill yes)
				)
			)
		)
		(pad "2" smd custom
			(at 0 0.4445 270)
			(size 0.1524 0.1524)
			(layers "B.Cu" "B.Mask" "B.Paste")
			(net "GND")
			(options
				(clearance outline)
				(anchor circle)
			)
			(primitives
				(gr_poly
					(pts
						(arc
							(start 0.3048 0.2032)
							(mid 0.275042 0.275042)
							(end 0.2032 0.3048)
						)
						(arc
							(start -0.2032 0.3048)
							(mid -0.275042 0.275042)
							(end -0.3048 0.2032)
						)
						(arc
							(start -0.3048 -0.2032)
							(mid -0.275042 -0.275042)
							(end -0.2032 -0.3048)
						)
						(arc
							(start 0.2032 -0.3048)
							(mid 0.275042 -0.275042)
							(end 0.3048 -0.2032)
						)
					)
					(width 0)
					(fill yes)
				)
			)
		)
	)
	(footprint ""
		(layer "B.Cu")
		(at 224.989644 -68.51523 90)
		(property "Reference" "C639"
			(at 0 0 90)
			(layer "B.SilkS")
			(hide yes)
			(effects
				(font
					(size 1.27 1.27)
				)
				(justify mirror)
			)
		)
		(property "Value" "SCD1U16V2KX-3GP"
			(at -1.1811 -2.7051 90)
			(unlocked yes)
			(layer "B.Fab")
			(hide yes)
			(effects
				(font
					(size 1.016 1.016)
					(thickness 0.1524)
				)
				(justify mirror)
			)
		)
		(property "Device Type" "C402H22"
			(at -1.1811 -4.2291 90)
			(unlocked yes)
			(layer "B.Fab")
			(hide yes)
			(effects
				(font
					(size 1.016 1.016)
					(thickness 0.1524)
				)
				(justify mirror)
			)
		)
		(duplicate_pad_numbers_are_jumpers no)
		(fp_rect
			(start 0.4318 0.9525)
			(end -0.4318 -0.9525)
			(stroke
				(width 0)
				(type default)
			)
			(fill no)
			(layer "B.CrtYd")
		)
		(fp_rect
			(start 0.4318 0.9525)
			(end -0.4318 -0.9525)
			(stroke
				(width 0)
				(type default)
			)
			(fill no)
			(layer "B.Fab")
		)
		(pad "1" smd custom
			(at 0 -0.4445 270)
			(size 0.1524 0.1524)
			(layers "B.Cu" "B.Mask" "B.Paste")
			(net "P3V3_M2")
			(options
				(clearance outline)
				(anchor circle)
			)
			(primitives
				(gr_poly
					(pts
						(arc
							(start 0.3048 0.2032)
							(mid 0.275042 0.275042)
							(end 0.2032 0.3048)
						)
						(arc
							(start -0.2032 0.3048)
							(mid -0.275042 0.275042)
							(end -0.3048 0.2032)
						)
						(arc
							(start -0.3048 -0.2032)
							(mid -0.275042 -0.275042)
							(end -0.2032 -0.3048)
						)
						(arc
							(start 0.2032 -0.3048)
							(mid 0.275042 -0.275042)
							(end 0.3048 -0.2032)
						)
					)
					(width 0)
					(fill yes)
				)
			)
		)
		(pad "2" smd custom
			(at 0 0.4445 270)
			(size 0.1524 0.1524)
			(layers "B.Cu" "B.Mask" "B.Paste")
			(net "GND")
			(options
				(clearance outline)
				(anchor circle)
			)
			(primitives
				(gr_poly
					(pts
						(arc
							(start 0.3048 0.2032)
							(mid 0.275042 0.275042)
							(end 0.2032 0.3048)
						)
						(arc
							(start -0.2032 0.3048)
							(mid -0.275042 0.275042)
							(end -0.3048 0.2032)
						)
						(arc
							(start -0.3048 -0.2032)
							(mid -0.275042 -0.275042)
							(end -0.2032 -0.3048)
						)
						(arc
							(start 0.2032 -0.3048)
							(mid 0.275042 -0.275042)
							(end 0.3048 -0.2032)
						)
					)
					(width 0)
					(fill yes)
				)
			)
		)
	)
	(footprint ""
		(layer "B.Cu")
		(at 19.15287 -131.007358 180)
		(property "Reference" "R236"
			(at 0 0 0)
			(layer "B.SilkS")
			(hide yes)
			(effects
				(font
					(size 1.27 1.27)
				)
				(justify mirror)
			)
		)
		(property "Value" "120R2F-GP"
			(at -0.064008 -3.993896 180)
			(unlocked yes)
			(layer "B.Fab")
			(hide yes)
			(effects
				(font
					(size 1.016 1.016)
					(thickness 0.1524)
				)
				(justify mirror)
			)
		)
		(property "Device Type" "R402H16"
			(at -0.064008 -5.517896 180)
			(unlocked yes)
			(layer "B.Fab")
			(hide yes)
			(effects
				(font
					(size 1.016 1.016)
					(thickness 0.1524)
				)
				(justify mirror)
			)
		)
		(duplicate_pad_numbers_are_jumpers no)
		(fp_line
			(start 0.508 -0.9398)
			(end 0.508 0.9398)
			(stroke
				(width 0.1524)
				(type default)
			)
			(layer "B.SilkS")
		)
		(fp_line
			(start -0.508 -0.9398)
			(end 0.508 -0.9398)
			(stroke
				(width 0.1524)
				(type default)
			)
			(layer "B.SilkS")
		)
		(fp_rect
			(start 0.508 0.9398)
			(end -0.508 -0.9398)
			(stroke
				(width 0)
				(type default)
			)
			(fill no)
			(layer "B.CrtYd")
		)
		(fp_rect
			(start 0.508 0.9398)
			(end -0.508 -0.9398)
			(stroke
				(width 0)
				(type default)
			)
			(fill no)
			(layer "B.Fab")
		)
		(pad "1" smd custom
			(at 0 -0.4445)
			(size 0.1397 0.1397)
			(layers "B.Cu" "B.Mask" "B.Paste")
			(net "MEMA_1")
			(options
				(clearance outline)
				(anchor circle)
			)
			(primitives
				(gr_poly
					(pts
						(arc
							(start -0.1778 0.2794)
							(mid -0.249642 0.249642)
							(end -0.2794 0.1778)
						)
						(arc
							(start -0.2794 -0.1778)
							(mid -0.249642 -0.249642)
							(end -0.1778 -0.2794)
						)
						(arc
							(start 0.1778 -0.2794)
							(mid 0.249642 -0.249642)
							(end 0.2794 -0.1778)
						)
						(arc
							(start 0.2794 0.1778)
							(mid 0.249642 0.249642)
							(end 0.1778 0.2794)
						)
					)
					(width 0)
					(fill yes)
				)
			)
		)
		(pad "2" smd custom
			(at 0 0.4445)
			(size 0.1397 0.1397)
			(layers "B.Cu" "B.Mask" "B.Paste")
			(net "P1V2_STBY")
			(options
				(clearance outline)
				(anchor circle)
			)
			(primitives
				(gr_poly
					(pts
						(arc
							(start -0.1778 0.2794)
							(mid -0.249642 0.249642)
							(end -0.2794 0.1778)
						)
						(arc
							(start -0.2794 -0.1778)
							(mid -0.249642 -0.249642)
							(end -0.1778 -0.2794)
						)
						(arc
							(start 0.1778 -0.2794)
							(mid 0.249642 -0.249642)
							(end 0.2794 -0.1778)
						)
						(arc
							(start 0.2794 0.1778)
							(mid 0.249642 0.249642)
							(end 0.1778 0.2794)
						)
					)
					(width 0)
					(fill yes)
				)
			)
		)
	)
	(footprint ""
		(layer "B.Cu")
		(at 83.194652 -152.914096 180)
		(property "Reference" "C39"
			(at 0 0 0)
			(layer "B.SilkS")
			(hide yes)
			(effects
				(font
					(size 1.27 1.27)
				)
				(justify mirror)
			)
		)
		(property "Value" "SCD1U16V2KX-3GP"
			(at -1.1811 -2.7051 180)
			(unlocked yes)
			(layer "B.Fab")
			(hide yes)
			(effects
				(font
					(size 1.016 1.016)
					(thickness 0.1524)
				)
				(justify mirror)
			)
		)
		(property "Device Type" "C402H22"
			(at -1.1811 -4.2291 180)
			(unlocked yes)
			(layer "B.Fab")
			(hide yes)
			(effects
				(font
					(size 1.016 1.016)
					(thickness 0.1524)
				)
				(justify mirror)
			)
		)
		(duplicate_pad_numbers_are_jumpers no)
		(fp_rect
			(start 0.4318 0.9525)
			(end -0.4318 -0.9525)
			(stroke
				(width 0)
				(type default)
			)
			(fill no)
			(layer "B.CrtYd")
		)
		(fp_rect
			(start 0.4318 0.9525)
			(end -0.4318 -0.9525)
			(stroke
				(width 0)
				(type default)
			)
			(fill no)
			(layer "B.Fab")
		)
		(pad "1" smd custom
			(at 0 -0.4445)
			(size 0.1524 0.1524)
			(layers "B.Cu" "B.Mask" "B.Paste")
			(net "P3V3_STBY")
			(options
				(clearance outline)
				(anchor circle)
			)
			(primitives
				(gr_poly
					(pts
						(arc
							(start 0.3048 0.2032)
							(mid 0.275042 0.275042)
							(end 0.2032 0.3048)
						)
						(arc
							(start -0.2032 0.3048)
							(mid -0.275042 0.275042)
							(end -0.3048 0.2032)
						)
						(arc
							(start -0.3048 -0.2032)
							(mid -0.275042 -0.275042)
							(end -0.2032 -0.3048)
						)
						(arc
							(start 0.2032 -0.3048)
							(mid 0.275042 -0.275042)
							(end 0.3048 -0.2032)
						)
					)
					(width 0)
					(fill yes)
				)
			)
		)
		(pad "2" smd custom
			(at 0 0.4445)
			(size 0.1524 0.1524)
			(layers "B.Cu" "B.Mask" "B.Paste")
			(net "GND")
			(options
				(clearance outline)
				(anchor circle)
			)
			(primitives
				(gr_poly
					(pts
						(arc
							(start 0.3048 0.2032)
							(mid 0.275042 0.275042)
							(end 0.2032 0.3048)
						)
						(arc
							(start -0.2032 0.3048)
							(mid -0.275042 0.275042)
							(end -0.3048 0.2032)
						)
						(arc
							(start -0.3048 -0.2032)
							(mid -0.275042 -0.275042)
							(end -0.2032 -0.3048)
						)
						(arc
							(start 0.2032 -0.3048)
							(mid 0.275042 -0.275042)
							(end 0.3048 -0.2032)
						)
					)
					(width 0)
					(fill yes)
				)
			)
		)
	)
	(footprint ""
		(layer "B.Cu")
		(at 50.1396 -163.2712 90)
		(property "Reference" "R191"
			(at 0 0 90)
			(layer "B.SilkS")
			(hide yes)
			(effects
				(font
					(size 1.27 1.27)
				)
				(justify mirror)
			)
		)
		(property "Value" "2K2R2F-GP"
			(at -0.064008 -3.993896 90)
			(unlocked yes)
			(layer "B.Fab")
			(hide yes)
			(effects
				(font
					(size 1.016 1.016)
					(thickness 0.1524)
				)
				(justify mirror)
			)
		)
		(property "Device Type" "R402H16"
			(at -0.064008 -5.517896 90)
			(unlocked yes)
			(layer "B.Fab")
			(hide yes)
			(effects
				(font
					(size 1.016 1.016)
					(thickness 0.1524)
				)
				(justify mirror)
			)
		)
		(duplicate_pad_numbers_are_jumpers no)
		(fp_line
			(start 0.508 -0.9398)
			(end 0.508 0.9398)
			(stroke
				(width 0.1524)
				(type default)
			)
			(layer "B.SilkS")
		)
		(fp_line
			(start -0.508 -0.9398)
			(end 0.508 -0.9398)
			(stroke
				(width 0.1524)
				(type default)
			)
			(layer "B.SilkS")
		)
		(fp_rect
			(start 0.508 0.9398)
			(end -0.508 -0.9398)
			(stroke
				(width 0)
				(type default)
			)
			(fill no)
			(layer "B.CrtYd")
		)
		(fp_rect
			(start 0.508 0.9398)
			(end -0.508 -0.9398)
			(stroke
				(width 0)
				(type default)
			)
			(fill no)
			(layer "B.Fab")
		)
		(pad "1" smd custom
			(at 0 -0.4445 270)
			(size 0.1397 0.1397)
			(layers "B.Cu" "B.Mask" "B.Paste")
			(net "I2C_MEZZ_OOB_SCL")
			(options
				(clearance outline)
				(anchor circle)
			)
			(primitives
				(gr_poly
					(pts
						(arc
							(start -0.1778 0.2794)
							(mid -0.249642 0.249642)
							(end -0.2794 0.1778)
						)
						(arc
							(start -0.2794 -0.1778)
							(mid -0.249642 -0.249642)
							(end -0.1778 -0.2794)
						)
						(arc
							(start 0.1778 -0.2794)
							(mid 0.249642 -0.249642)
							(end 0.2794 -0.1778)
						)
						(arc
							(start 0.2794 0.1778)
							(mid 0.249642 0.249642)
							(end 0.1778 0.2794)
						)
					)
					(width 0)
					(fill yes)
				)
			)
		)
		(pad "2" smd custom
			(at 0 0.4445 270)
			(size 0.1397 0.1397)
			(layers "B.Cu" "B.Mask" "B.Paste")
			(net "P3V3_STBY")
			(options
				(clearance outline)
				(anchor circle)
			)
			(primitives
				(gr_poly
					(pts
						(arc
							(start -0.1778 0.2794)
							(mid -0.249642 0.249642)
							(end -0.2794 0.1778)
						)
						(arc
							(start -0.2794 -0.1778)
							(mid -0.249642 -0.249642)
							(end -0.1778 -0.2794)
						)
						(arc
							(start 0.1778 -0.2794)
							(mid 0.249642 -0.249642)
							(end 0.2794 -0.1778)
						)
						(arc
							(start 0.2794 0.1778)
							(mid 0.249642 0.249642)
							(end 0.1778 0.2794)
						)
					)
					(width 0)
					(fill yes)
				)
			)
		)
	)
	(footprint ""
		(layer "B.Cu")
		(at 90.678 -149.479)
		(property "Reference" "R40"
			(at 0 0 0)
			(layer "B.SilkS")
			(hide yes)
			(effects
				(font
					(size 1.27 1.27)
				)
				(justify mirror)
			)
		)
		(property "Value" "4K7R2F-GP"
			(at -0.064008 -3.993896 0)
			(unlocked yes)
			(layer "B.Fab")
			(hide yes)
			(effects
				(font
					(size 1.016 1.016)
					(thickness 0.1524)
				)
				(justify mirror)
			)
		)
		(property "Device Type" "R402H16"
			(at -0.064008 -5.517896 0)
			(unlocked yes)
			(layer "B.Fab")
			(hide yes)
			(effects
				(font
					(size 1.016 1.016)
					(thickness 0.1524)
				)
				(justify mirror)
			)
		)
		(duplicate_pad_numbers_are_jumpers no)
		(fp_line
			(start -0.508 -0.9398)
			(end 0.508 -0.9398)
			(stroke
				(width 0.1524)
				(type default)
			)
			(layer "B.SilkS")
		)
		(fp_line
			(start 0.508 -0.9398)
			(end 0.508 0.9398)
			(stroke
				(width 0.1524)
				(type default)
			)
			(layer "B.SilkS")
		)
		(fp_rect
			(start 0.508 0.9398)
			(end -0.508 -0.9398)
			(stroke
				(width 0)
				(type default)
			)
			(fill no)
			(layer "B.CrtYd")
		)
		(fp_rect
			(start 0.508 0.9398)
			(end -0.508 -0.9398)
			(stroke
				(width 0)
				(type default)
			)
			(fill no)
			(layer "B.Fab")
		)
		(pad "1" smd custom
			(at 0 -0.4445 180)
			(size 0.1397 0.1397)
			(layers "B.Cu" "B.Mask" "B.Paste")
			(net "USB_EN_1")
			(options
				(clearance outline)
				(anchor circle)
			)
			(primitives
				(gr_poly
					(pts
						(arc
							(start -0.1778 0.2794)
							(mid -0.249642 0.249642)
							(end -0.2794 0.1778)
						)
						(arc
							(start -0.2794 -0.1778)
							(mid -0.249642 -0.249642)
							(end -0.1778 -0.2794)
						)
						(arc
							(start 0.1778 -0.2794)
							(mid 0.249642 -0.249642)
							(end 0.2794 -0.1778)
						)
						(arc
							(start 0.2794 0.1778)
							(mid 0.249642 0.249642)
							(end 0.1778 0.2794)
						)
					)
					(width 0)
					(fill yes)
				)
			)
		)
		(pad "2" smd custom
			(at 0 0.4445 180)
			(size 0.1397 0.1397)
			(layers "B.Cu" "B.Mask" "B.Paste")
			(net "GND")
			(options
				(clearance outline)
				(anchor circle)
			)
			(primitives
				(gr_poly
					(pts
						(arc
							(start -0.1778 0.2794)
							(mid -0.249642 0.249642)
							(end -0.2794 0.1778)
						)
						(arc
							(start -0.2794 -0.1778)
							(mid -0.249642 -0.249642)
							(end -0.1778 -0.2794)
						)
						(arc
							(start 0.1778 -0.2794)
							(mid 0.249642 -0.249642)
							(end 0.2794 -0.1778)
						)
						(arc
							(start 0.2794 0.1778)
							(mid 0.249642 0.249642)
							(end 0.1778 0.2794)
						)
					)
					(width 0)
					(fill yes)
				)
			)
		)
	)
)
